(kicad_pcb
	(version 20260206)
	(generator "pcbnew")
	(generator_version "10.0")
	(general
		(thickness 1.6)
		(legacy_teardrops no)
	)
	(paper "A4")
	(title_block
		(title "Bryce Canyon_F.DPB_16315-1-OCP.brd")
		(comment 1 "Bryce Canyon / footprints 1116-1120 of 2223")
	)
	(layers
		(0 "F.Cu" signal "TOP")
		(4 "In1.Cu" signal "L2GND")
		(6 "In2.Cu" signal "L3")
		(8 "In3.Cu" signal "L4GND")
		(10 "In4.Cu" signal "L5")
		(12 "In5.Cu" signal "L6VCC")
		(14 "In6.Cu" signal "L7VCC")
		(16 "In7.Cu" signal "L8")
		(18 "In8.Cu" signal "L9GND")
		(20 "In9.Cu" signal "L10")
		(22 "In10.Cu" signal "L11GND")
		(2 "B.Cu" signal "BOTTOM")
		(9 "F.Adhes" user "F.Adhesive")
		(11 "B.Adhes" user "B.Adhesive")
		(13 "F.Paste" user "Package Geometry/Pastemask Top")
		(15 "B.Paste" user "Package Geometry/Pastemask Bottom")
		(5 "F.SilkS" user "Ref Des/Silkscreen Top")
		(7 "B.SilkS" user "Ref Des/Silkscreen Bottom")
		(1 "F.Mask" user "Board Geometry/Soldermask Top")
		(3 "B.Mask" user "Board Geometry/Soldermask Bottom")
		(17 "Dwgs.User" user "User.Drawings")
		(19 "Cmts.User" user "User.Comments")
		(21 "Eco1.User" user "User.Eco1")
		(23 "Eco2.User" user "User.Eco2")
		(25 "Edge.Cuts" user "Board Geometry/Outline")
		(27 "Margin" user)
		(31 "F.CrtYd" user "Package Geometry/Place Bound Top")
		(29 "B.CrtYd" user "Package Geometry/Place Bound Bottom")
		(35 "F.Fab" user "Ref Des/Assembly Top")
		(33 "B.Fab" user "Ref Des/Assembly Bottom")
	)
	(footprint ""
		(layer "F.Cu")
		(at 6.80593 -287.4391)
		(property "Reference" "Q287"
			(at 0 0 0)
			(layer "F.SilkS")
			(hide yes)
			(effects
				(font
					(size 1.27 1.27)
				)
			)
		)
		(property "Value" "SSM3K324R-GP"
			(at 0.127 -8.9662 0)
			(unlocked yes)
			(layer "F.Fab")
			(hide yes)
			(effects
				(font
					(size 1.016 1.016)
					(thickness 0.1524)
				)
			)
		)
		(property "Device Type" "SOT23DGS2D4H35"
			(at 0.127 -10.4902 0)
			(unlocked yes)
			(layer "F.Fab")
			(hide yes)
			(effects
				(font
					(size 1.016 1.016)
					(thickness 0.1524)
				)
			)
		)
		(duplicate_pad_numbers_are_jumpers no)
		(fp_line
			(start -1.651 -1.778)
			(end -1.651 1.778)
			(stroke
				(width 0.1524)
				(type default)
			)
			(layer "F.SilkS")
		)
		(fp_line
			(start -1.651 1.778)
			(end 1.651 1.778)
			(stroke
				(width 0.1524)
				(type default)
			)
			(layer "F.SilkS")
		)
		(fp_line
			(start 1.651 -1.778)
			(end -1.651 -1.778)
			(stroke
				(width 0.1524)
				(type default)
			)
			(layer "F.SilkS")
		)
		(fp_line
			(start 1.651 1.778)
			(end 1.651 -1.778)
			(stroke
				(width 0.1524)
				(type default)
			)
			(layer "F.SilkS")
		)
		(fp_poly
			(pts
				(xy -1.778 1.8796) (xy -1.778 -1.8796) (xy 1.778 -1.8796) (xy 1.778 1.8796)
			)
			(stroke
				(width 0)
				(type default)
			)
			(fill no)
			(layer "F.CrtYd")
		)
		(fp_poly
			(pts
				(xy -1.778 1.8796) (xy -1.778 -1.8796) (xy 1.778 -1.8796) (xy 1.778 1.8796)
			)
			(stroke
				(width 0)
				(type default)
			)
			(fill no)
			(layer "F.Fab")
		)
		(pad "D" smd custom
			(at 0 -0.9525)
			(size 0.1905 0.1905)
			(layers "F.Cu" "F.Mask" "F.Paste")
			(net "DRV_ACT_24_N")
			(options
				(clearance outline)
				(anchor circle)
			)
			(primitives
				(gr_poly
					(pts
						(arc
							(start -0.1778 0.5715)
							(mid -0.321484 0.511984)
							(end -0.381 0.3683)
						)
						(arc
							(start -0.381 -0.3683)
							(mid -0.321484 -0.511984)
							(end -0.1778 -0.5715)
						)
						(arc
							(start 0.1778 -0.5715)
							(mid 0.321484 -0.511984)
							(end 0.381 -0.3683)
						)
						(arc
							(start 0.381 0.3683)
							(mid 0.321484 0.511984)
							(end 0.1778 0.5715)
						)
					)
					(width 0)
					(fill yes)
				)
			)
		)
		(pad "G" smd custom
			(at -0.98425 0.9525)
			(size 0.1905 0.1905)
			(layers "F.Cu" "F.Mask" "F.Paste")
			(net "DRIVE_B_24_ACT")
			(options
				(clearance outline)
				(anchor circle)
			)
			(primitives
				(gr_poly
					(pts
						(arc
							(start -0.1778 0.5715)
							(mid -0.321484 0.511984)
							(end -0.381 0.3683)
						)
						(arc
							(start -0.381 -0.3683)
							(mid -0.321484 -0.511984)
							(end -0.1778 -0.5715)
						)
						(arc
							(start 0.1778 -0.5715)
							(mid 0.321484 -0.511984)
							(end 0.381 -0.3683)
						)
						(arc
							(start 0.381 0.3683)
							(mid 0.321484 0.511984)
							(end 0.1778 0.5715)
						)
					)
					(width 0)
					(fill yes)
				)
			)
		)
		(pad "S" smd custom
			(at 0.98425 0.9525)
			(size 0.1905 0.1905)
			(layers "F.Cu" "F.Mask" "F.Paste")
			(net "GND")
			(options
				(clearance outline)
				(anchor circle)
			)
			(primitives
				(gr_poly
					(pts
						(arc
							(start -0.1778 0.5715)
							(mid -0.321484 0.511984)
							(end -0.381 0.3683)
						)
						(arc
							(start -0.381 -0.3683)
							(mid -0.321484 -0.511984)
							(end -0.1778 -0.5715)
						)
						(arc
							(start 0.1778 -0.5715)
							(mid 0.321484 -0.511984)
							(end 0.381 -0.3683)
						)
						(arc
							(start 0.381 0.3683)
							(mid 0.321484 0.511984)
							(end 0.1778 0.5715)
						)
					)
					(width 0)
					(fill yes)
				)
			)
		)
	)
	(footprint ""
		(layer "F.Cu")
		(at 447.16573 -256.811018 90)
		(property "Reference" "R1253"
			(at 0 0 90)
			(layer "F.SilkS")
			(hide yes)
			(effects
				(font
					(size 1.27 1.27)
				)
			)
		)
		(property "Value" "100KR2F-L1-GP"
			(at 0.064008 -3.993896 90)
			(unlocked yes)
			(layer "F.Fab")
			(hide yes)
			(effects
				(font
					(size 1.016 1.016)
					(thickness 0.1524)
				)
			)
		)
		(property "Device Type" "R402H16"
			(at 0.064008 -5.517896 90)
			(unlocked yes)
			(layer "F.Fab")
			(hide yes)
			(effects
				(font
					(size 1.016 1.016)
					(thickness 0.1524)
				)
			)
		)
		(duplicate_pad_numbers_are_jumpers no)
		(fp_line
			(start 0.508 -0.9398)
			(end -0.508 -0.9398)
			(stroke
				(width 0.1524)
				(type default)
			)
			(layer "F.SilkS")
		)
		(fp_line
			(start -0.508 -0.9398)
			(end -0.508 0.9398)
			(stroke
				(width 0.1524)
				(type default)
			)
			(layer "F.SilkS")
		)
		(fp_rect
			(start -0.508 0.9398)
			(end 0.508 -0.9398)
			(stroke
				(width 0)
				(type default)
			)
			(fill no)
			(layer "F.CrtYd")
		)
		(fp_rect
			(start -0.508 0.9398)
			(end 0.508 -0.9398)
			(stroke
				(width 0)
				(type default)
			)
			(fill no)
			(layer "F.Fab")
		)
		(pad "1" smd custom
			(at 0 -0.4445 90)
			(size 0.1397 0.1397)
			(layers "F.Cu" "F.Mask" "F.Paste")
			(net "AGND_P5V_C")
			(options
				(clearance outline)
				(anchor circle)
			)
			(primitives
				(gr_poly
					(pts
						(arc
							(start -0.1778 -0.2794)
							(mid -0.249642 -0.249642)
							(end -0.2794 -0.1778)
						)
						(arc
							(start -0.2794 0.1778)
							(mid -0.249642 0.249642)
							(end -0.1778 0.2794)
						)
						(arc
							(start 0.1778 0.2794)
							(mid 0.249642 0.249642)
							(end 0.2794 0.1778)
						)
						(arc
							(start 0.2794 -0.1778)
							(mid 0.249642 -0.249642)
							(end 0.1778 -0.2794)
						)
					)
					(width 0)
					(fill yes)
				)
			)
		)
		(pad "2" smd custom
			(at 0 0.4445 90)
			(size 0.1397 0.1397)
			(layers "F.Cu" "F.Mask" "F.Paste")
			(net "P5V_C_MODE")
			(options
				(clearance outline)
				(anchor circle)
			)
			(primitives
				(gr_poly
					(pts
						(arc
							(start -0.1778 -0.2794)
							(mid -0.249642 -0.249642)
							(end -0.2794 -0.1778)
						)
						(arc
							(start -0.2794 0.1778)
							(mid -0.249642 0.249642)
							(end -0.1778 0.2794)
						)
						(arc
							(start 0.1778 0.2794)
							(mid 0.249642 0.249642)
							(end 0.2794 0.1778)
						)
						(arc
							(start 0.2794 -0.1778)
							(mid 0.249642 -0.249642)
							(end 0.1778 -0.2794)
						)
					)
					(width 0)
					(fill yes)
				)
			)
		)
	)
	(footprint ""
		(layer "F.Cu")
		(at 81.600548 -275.633942)
		(property "Reference" "R193"
			(at 0 0 0)
			(layer "F.SilkS")
			(hide yes)
			(effects
				(font
					(size 1.27 1.27)
				)
			)
		)
		(property "Value" "0R2J-2-GP"
			(at 0.064008 -3.993896 0)
			(unlocked yes)
			(layer "F.Fab")
			(hide yes)
			(effects
				(font
					(size 1.016 1.016)
					(thickness 0.1524)
				)
			)
		)
		(property "Device Type" "R402H16"
			(at 0.064008 -5.517896 0)
			(unlocked yes)
			(layer "F.Fab")
			(hide yes)
			(effects
				(font
					(size 1.016 1.016)
					(thickness 0.1524)
				)
			)
		)
		(duplicate_pad_numbers_are_jumpers no)
		(fp_line
			(start -0.508 -0.9398)
			(end -0.508 0.9398)
			(stroke
				(width 0.1524)
				(type default)
			)
			(layer "F.SilkS")
		)
		(fp_line
			(start 0.508 -0.9398)
			(end -0.508 -0.9398)
			(stroke
				(width 0.1524)
				(type default)
			)
			(layer "F.SilkS")
		)
		(fp_rect
			(start -0.508 0.9398)
			(end 0.508 -0.9398)
			(stroke
				(width 0)
				(type default)
			)
			(fill no)
			(layer "F.CrtYd")
		)
		(fp_rect
			(start -0.508 0.9398)
			(end 0.508 -0.9398)
			(stroke
				(width 0)
				(type default)
			)
			(fill no)
			(layer "F.Fab")
		)
		(pad "1" smd custom
			(at 0 -0.4445)
			(size 0.1397 0.1397)
			(layers "F.Cu" "F.Mask" "F.Paste")
			(net "SW_HDD_G2")
			(options
				(clearance outline)
				(anchor circle)
			)
			(primitives
				(gr_poly
					(pts
						(arc
							(start -0.1778 -0.2794)
							(mid -0.249642 -0.249642)
							(end -0.2794 -0.1778)
						)
						(arc
							(start -0.2794 0.1778)
							(mid -0.249642 0.249642)
							(end -0.1778 0.2794)
						)
						(arc
							(start 0.1778 0.2794)
							(mid 0.249642 0.249642)
							(end 0.2794 0.1778)
						)
						(arc
							(start 0.2794 -0.1778)
							(mid 0.249642 -0.249642)
							(end 0.1778 -0.2794)
						)
					)
					(width 0)
					(fill yes)
				)
			)
		)
		(pad "2" smd custom
			(at 0 0.4445)
			(size 0.1397 0.1397)
			(layers "F.Cu" "F.Mask" "F.Paste")
			(net "SW_HDD_R2")
			(options
				(clearance outline)
				(anchor circle)
			)
			(primitives
				(gr_poly
					(pts
						(arc
							(start -0.1778 -0.2794)
							(mid -0.249642 -0.249642)
							(end -0.2794 -0.1778)
						)
						(arc
							(start -0.2794 0.1778)
							(mid -0.249642 0.249642)
							(end -0.1778 0.2794)
						)
						(arc
							(start 0.1778 0.2794)
							(mid 0.249642 0.249642)
							(end 0.2794 0.1778)
						)
						(arc
							(start 0.2794 -0.1778)
							(mid 0.249642 -0.249642)
							(end 0.1778 -0.2794)
						)
					)
					(width 0)
					(fill yes)
				)
			)
		)
	)
	(footprint ""
		(layer "F.Cu")
		(at 272.3388 -13.208 180)
		(property "Reference" "TP196"
			(at 0 0 180)
			(layer "F.SilkS")
			(hide yes)
			(effects
				(font
					(size 1.27 1.27)
				)
			)
		)
		(property "Value" "TPAD32-GP"
			(at -0.0508 -1.6764 180)
			(unlocked yes)
			(layer "F.Fab")
			(hide yes)
			(effects
				(font
					(size 1.016 1.016)
					(thickness 0.1524)
				)
			)
		)
		(property "Device Type" "TPAD32"
			(at -0.0508 -3.2004 180)
			(unlocked yes)
			(layer "F.Fab")
			(hide yes)
			(effects
				(font
					(size 1.016 1.016)
					(thickness 0.1524)
				)
			)
		)
		(duplicate_pad_numbers_are_jumpers no)
		(fp_poly
			(pts
				(arc
					(start -0.4064 0)
					(mid 0.4064 0)
					(end -0.4064 0)
				)
			)
			(stroke
				(width 0)
				(type default)
			)
			(fill no)
			(layer "F.CrtYd")
		)
		(fp_poly
			(pts
				(arc
					(start -0.7112 0)
					(mid 0.7112 0)
					(end -0.7112 0)
				)
			)
			(stroke
				(width 0)
				(type default)
			)
			(fill no)
			(layer "F.Fab")
		)
		(pad "1" smd circle
			(at 0 0 180)
			(size 0.8128 0.8128)
			(layers "F.Cu" "F.Mask" "F.Paste")
			(net "TP_COMP_B_NCSI_RXER")
		)
	)
	(footprint ""
		(layer "F.Cu")
		(at 240.284 -249.174)
		(property "Reference" "R52"
			(at 0 0 0)
			(layer "F.SilkS")
			(hide yes)
			(effects
				(font
					(size 1.27 1.27)
				)
			)
		)
		(property "Value" "0R2J-2-GP"
			(at 0.064008 -3.993896 0)
			(unlocked yes)
			(layer "F.Fab")
			(hide yes)
			(effects
				(font
					(size 1.016 1.016)
					(thickness 0.1524)
				)
			)
		)
		(property "Device Type" "R402H16"
			(at 0.064008 -5.517896 0)
			(unlocked yes)
			(layer "F.Fab")
			(hide yes)
			(effects
				(font
					(size 1.016 1.016)
					(thickness 0.1524)
				)
			)
		)
		(duplicate_pad_numbers_are_jumpers no)
		(fp_line
			(start -0.508 -0.9398)
			(end -0.508 0.9398)
			(stroke
				(width 0.1524)
				(type default)
			)
			(layer "F.SilkS")
		)
		(fp_line
			(start 0.508 -0.9398)
			(end -0.508 -0.9398)
			(stroke
				(width 0.1524)
				(type default)
			)
			(layer "F.SilkS")
		)
		(fp_rect
			(start -0.508 0.9398)
			(end 0.508 -0.9398)
			(stroke
				(width 0)
				(type default)
			)
			(fill no)
			(layer "F.CrtYd")
		)
		(fp_rect
			(start -0.508 0.9398)
			(end 0.508 -0.9398)
			(stroke
				(width 0)
				(type default)
			)
			(fill no)
			(layer "F.Fab")
		)
		(pad "1" smd custom
			(at 0 -0.4445)
			(size 0.1397 0.1397)
			(layers "F.Cu" "F.Mask" "F.Paste")
			(net "IO_EXP5_INT_N")
			(options
				(clearance outline)
				(anchor circle)
			)
			(primitives
				(gr_poly
					(pts
						(arc
							(start -0.1778 -0.2794)
							(mid -0.249642 -0.249642)
							(end -0.2794 -0.1778)
						)
						(arc
							(start -0.2794 0.1778)
							(mid -0.249642 0.249642)
							(end -0.1778 0.2794)
						)
						(arc
							(start 0.1778 0.2794)
							(mid 0.249642 0.249642)
							(end 0.2794 0.1778)
						)
						(arc
							(start 0.2794 -0.1778)
							(mid 0.249642 -0.249642)
							(end 0.1778 -0.2794)
						)
					)
					(width 0)
					(fill yes)
				)
			)
		)
		(pad "2" smd custom
			(at 0 0.4445)
			(size 0.1397 0.1397)
			(layers "F.Cu" "F.Mask" "F.Paste")
			(net "DRIVE_INSERT_ALERT_A_N")
			(options
				(clearance outline)
				(anchor circle)
			)
			(primitives
				(gr_poly
					(pts
						(arc
							(start -0.1778 -0.2794)
							(mid -0.249642 -0.249642)
							(end -0.2794 -0.1778)
						)
						(arc
							(start -0.2794 0.1778)
							(mid -0.249642 0.249642)
							(end -0.1778 0.2794)
						)
						(arc
							(start 0.1778 0.2794)
							(mid 0.249642 0.249642)
							(end 0.2794 0.1778)
						)
						(arc
							(start 0.2794 -0.1778)
							(mid 0.249642 -0.249642)
							(end 0.1778 -0.2794)
						)
					)
					(width 0)
					(fill yes)
				)
			)
		)
	)
)
